# T6G (Grand Teton) — schematic netlist excerpt (pin names and nets, part order shuffled) for the footprints in the layout excerpt that follows; sources: Cadence DE-HDL packaged netlist, KiCad conversion of 04192023_DAF0TMB3IC0_F0TG_MB_C_brd_V02_OCP.brd

PR5481  Q_RES  4.53K 1% CHIP  pkg 0402LF  page 134 : A = P3V3_OCP_SENSE_1 ; B = GND
R351  Q_RES  33 5% CHIP  pkg 0402LF  page 151 : A = SMB_SCM_2_R5_SCL ; B = SMB_SCM_2_R6_SCL

(kicad_pcb
	(version 20260206)
	(generator "pcbnew")
	(generator_version "10.0")
	(general
		(thickness 1.6)
		(legacy_teardrops no)
	)
	(paper "A4")
	(title_block
		(title "04192023_DAF0TMB3IC0_F0TG_MB_C_brd_V02_OCP.brd")
		(comment 1 "Grand Teton / footprints 3788-3789 of 8354")
	)
	(layers
		(0 "F.Cu" signal "TOP")
		(4 "In1.Cu" signal "GND")
		(6 "In2.Cu" signal "IN1")
		(8 "In3.Cu" signal "GND1")
		(10 "In4.Cu" signal "IN2")
		(12 "In5.Cu" signal "GND2")
		(14 "In6.Cu" signal "IN3")
		(16 "In7.Cu" signal "GND3")
		(18 "In8.Cu" signal "VCC")
		(20 "In9.Cu" signal "VCC1")
		(22 "In10.Cu" signal "GND4")
		(24 "In11.Cu" signal "IN4")
		(26 "In12.Cu" signal "GND5")
		(28 "In13.Cu" signal "IN5")
		(30 "In14.Cu" signal "GND6")
		(32 "In15.Cu" signal "IN6")
		(34 "In16.Cu" signal "GND7")
		(2 "B.Cu" signal "BOTTOM")
		(9 "F.Adhes" user "F.Adhesive")
		(11 "B.Adhes" user "B.Adhesive")
		(13 "F.Paste" user "Package Geometry/Pastemask Top")
		(15 "B.Paste" user "Package Geometry/Pastemask Bottom")
		(5 "F.SilkS" user "Ref Des/Silkscreen Top")
		(7 "B.SilkS" user "Ref Des/Silkscreen Bottom")
		(1 "F.Mask" user "Board Geometry/Soldermask Top")
		(3 "B.Mask" user "Board Geometry/Soldermask Bottom")
		(17 "Dwgs.User" user "User.Drawings")
		(19 "Cmts.User" user "User.Comments")
		(21 "Eco1.User" user "User.Eco1")
		(23 "Eco2.User" user "User.Eco2")
		(25 "Edge.Cuts" user "Board Geometry/Outline")
		(27 "Margin" user)
		(31 "F.CrtYd" user "Package Geometry/Place Bound Top")
		(29 "B.CrtYd" user "Package Geometry/Place Bound Bottom")
		(35 "F.Fab" user "Ref Des/Assembly Top")
		(33 "B.Fab" user "Ref Des/Assembly Bottom")
	)
	(footprint ""
		(layer "F.Cu")
		(at 432.974496 -109.13745 90)
		(property "Reference" "PR5481"
			(at 0 0 90)
			(layer "F.SilkS")
			(hide yes)
			(effects
				(font
					(size 1.27 1.27)
				)
			)
		)
		(property "Value" ""
			(at 0 0 90)
			(layer "F.Fab")
			(effects
				(font
					(size 1.27 1.27)
				)
			)
		)
		(duplicate_pad_numbers_are_jumpers no)
		(fp_line
			(start 0.7874 -0.4064)
			(end 0.7874 0.4064)
			(stroke
				(width 0.1524)
				(type default)
			)
			(layer "F.SilkS")
		)
		(fp_line
			(start -0.7874 -0.4064)
			(end 0.7874 -0.4064)
			(stroke
				(width 0.1524)
				(type default)
			)
			(layer "F.SilkS")
		)
		(fp_line
			(start 0.7874 0.4064)
			(end -0.7874 0.4064)
			(stroke
				(width 0.1524)
				(type default)
			)
			(layer "F.SilkS")
		)
		(fp_line
			(start -0.7874 0.4064)
			(end -0.7874 -0.4064)
			(stroke
				(width 0.1524)
				(type default)
			)
			(layer "F.SilkS")
		)
		(fp_line
			(start -0.12065 -0.305054)
			(end -0.12065 -0.2794)
			(stroke
				(width 0.1)
				(type default)
			)
			(layer "F.Fab")
		)
		(fp_line
			(start -0.67945 -0.305054)
			(end -0.12065 -0.305054)
			(stroke
				(width 0.1)
				(type default)
			)
			(layer "F.Fab")
		)
		(fp_line
			(start 0.67945 -0.3048)
			(end 0.67945 0.3048)
			(stroke
				(width 0.1)
				(type default)
			)
			(layer "F.Fab")
		)
		(fp_line
			(start 0.12065 -0.3048)
			(end 0.67945 -0.3048)
			(stroke
				(width 0.1)
				(type default)
			)
			(layer "F.Fab")
		)
		(fp_line
			(start 0.12065 -0.2794)
			(end 0.12065 -0.3048)
			(stroke
				(width 0.1)
				(type default)
			)
			(layer "F.Fab")
		)
		(fp_line
			(start -0.12065 -0.2794)
			(end 0.12065 -0.2794)
			(stroke
				(width 0.1)
				(type default)
			)
			(layer "F.Fab")
		)
		(fp_line
			(start 0.120396 0.2794)
			(end -0.12065 0.2794)
			(stroke
				(width 0.1)
				(type default)
			)
			(layer "F.Fab")
		)
		(fp_line
			(start -0.12065 0.2794)
			(end -0.12065 0.3048)
			(stroke
				(width 0.1)
				(type default)
			)
			(layer "F.Fab")
		)
		(fp_line
			(start 0.67945 0.3048)
			(end 0.120396 0.3048)
			(stroke
				(width 0.1)
				(type default)
			)
			(layer "F.Fab")
		)
		(fp_line
			(start 0.120396 0.3048)
			(end 0.120396 0.2794)
			(stroke
				(width 0.1)
				(type default)
			)
			(layer "F.Fab")
		)
		(fp_line
			(start -0.12065 0.3048)
			(end -0.67945 0.3048)
			(stroke
				(width 0.1)
				(type default)
			)
			(layer "F.Fab")
		)
		(fp_line
			(start -0.67945 0.3048)
			(end -0.67945 -0.305054)
			(stroke
				(width 0.1)
				(type default)
			)
			(layer "F.Fab")
		)
		(pad "1" smd circle
			(at -0.40005 0 90)
			(size 0 0)
			(layers "F.Cu" "F.Mask" "F.Paste")
			(net "P3V3_OCP_SENSE_1")
		)
		(pad "2" smd circle
			(at 0.40005 0 90)
			(size 0 0)
			(layers "F.Cu" "F.Mask" "F.Paste")
			(net "GND")
		)
	)
	(footprint ""
		(layer "F.Cu")
		(at 325.9074 -364.236)
		(property "Reference" "R351"
			(at 0 0 0)
			(layer "F.SilkS")
			(hide yes)
			(effects
				(font
					(size 1.27 1.27)
				)
			)
		)
		(property "Value" ""
			(at 0 0 0)
			(layer "F.Fab")
			(effects
				(font
					(size 1.27 1.27)
				)
			)
		)
		(duplicate_pad_numbers_are_jumpers no)
		(fp_line
			(start -0.7874 -0.4064)
			(end 0.7874 -0.4064)
			(stroke
				(width 0.1524)
				(type default)
			)
			(layer "F.SilkS")
		)
		(fp_line
			(start -0.7874 0.4064)
			(end -0.7874 -0.4064)
			(stroke
				(width 0.1524)
				(type default)
			)
			(layer "F.SilkS")
		)
		(fp_line
			(start 0.7874 -0.4064)
			(end 0.7874 0.4064)
			(stroke
				(width 0.1524)
				(type default)
			)
			(layer "F.SilkS")
		)
		(fp_line
			(start 0.7874 0.4064)
			(end -0.7874 0.4064)
			(stroke
				(width 0.1524)
				(type default)
			)
			(layer "F.SilkS")
		)
		(fp_line
			(start -0.67945 -0.305054)
			(end -0.12065 -0.305054)
			(stroke
				(width 0.1)
				(type default)
			)
			(layer "F.Fab")
		)
		(fp_line
			(start -0.67945 0.3048)
			(end -0.67945 -0.305054)
			(stroke
				(width 0.1)
				(type default)
			)
			(layer "F.Fab")
		)
		(fp_line
			(start -0.12065 -0.305054)
			(end -0.12065 -0.2794)
			(stroke
				(width 0.1)
				(type default)
			)
			(layer "F.Fab")
		)
		(fp_line
			(start -0.12065 -0.2794)
			(end 0.12065 -0.2794)
			(stroke
				(width 0.1)
				(type default)
			)
			(layer "F.Fab")
		)
		(fp_line
			(start -0.12065 0.2794)
			(end -0.12065 0.3048)
			(stroke
				(width 0.1)
				(type default)
			)
			(layer "F.Fab")
		)
		(fp_line
			(start -0.12065 0.3048)
			(end -0.67945 0.3048)
			(stroke
				(width 0.1)
				(type default)
			)
			(layer "F.Fab")
		)
		(fp_line
			(start 0.120396 0.2794)
			(end -0.12065 0.2794)
			(stroke
				(width 0.1)
				(type default)
			)
			(layer "F.Fab")
		)
		(fp_line
			(start 0.120396 0.3048)
			(end 0.120396 0.2794)
			(stroke
				(width 0.1)
				(type default)
			)
			(layer "F.Fab")
		)
		(fp_line
			(start 0.12065 -0.3048)
			(end 0.67945 -0.3048)
			(stroke
				(width 0.1)
				(type default)
			)
			(layer "F.Fab")
		)
		(fp_line
			(start 0.12065 -0.2794)
			(end 0.12065 -0.3048)
			(stroke
				(width 0.1)
				(type default)
			)
			(layer "F.Fab")
		)
		(fp_line
			(start 0.67945 -0.3048)
			(end 0.67945 0.3048)
			(stroke
				(width 0.1)
				(type default)
			)
			(layer "F.Fab")
		)
		(fp_line
			(start 0.67945 0.3048)
			(end 0.120396 0.3048)
			(stroke
				(width 0.1)
				(type default)
			)
			(layer "F.Fab")
		)
		(pad "1" smd circle
			(at -0.40005 0)
			(size 0 0)
			(layers "F.Cu" "F.Mask" "F.Paste")
			(net "SMB_SCM_2_R5_SCL")
		)
		(pad "2" smd circle
			(at 0.40005 0)
			(size 0 0)
			(layers "F.Cu" "F.Mask" "F.Paste")
			(net "SMB_SCM_2_R6_SCL")
		)
	)
)
